# T6G (Grand Teton) — schematic netlist excerpt (pin names and nets, part order shuffled) for the footprints in the layout excerpt that follows; sources: Cadence DE-HDL packaged netlist, KiCad conversion of 04192023_DAF0TMB3IC0_F0TG_MB_C_brd_V02_OCP.brd

C2126  Q_CAP  22UF 4V 20% X6S  pkg C0402  page 74 : A = PVDD11_S3_P1 ; B = GND

Q128  MOSFET_NCH_DUAL  PJT138K IC  pkg SOT363XD  page 125
  S1  = GND
  G1  = GPU_3V3IO_RSVD0_FFU
  D2  = GPU_3V3IO_RSVD0_FFU_ISO
  S2  = GND
  G2  = GPU_3V3IO_RSVD0_FFU_N
  D1  = GPU_3V3IO_RSVD0_FFU_N

(kicad_pcb
	(version 20260206)
	(generator "pcbnew")
	(generator_version "10.0")
	(general
		(thickness 1.6)
		(legacy_teardrops no)
	)
	(paper "A4")
	(title_block
		(title "04192023_DAF0TMB3IC0_F0TG_MB_C_brd_V02_OCP.brd")
		(comment 1 "Grand Teton / footprints 6886-6887 of 8354")
	)
	(layers
		(0 "F.Cu" signal "TOP")
		(4 "In1.Cu" signal "GND")
		(6 "In2.Cu" signal "IN1")
		(8 "In3.Cu" signal "GND1")
		(10 "In4.Cu" signal "IN2")
		(12 "In5.Cu" signal "GND2")
		(14 "In6.Cu" signal "IN3")
		(16 "In7.Cu" signal "GND3")
		(18 "In8.Cu" signal "VCC")
		(20 "In9.Cu" signal "VCC1")
		(22 "In10.Cu" signal "GND4")
		(24 "In11.Cu" signal "IN4")
		(26 "In12.Cu" signal "GND5")
		(28 "In13.Cu" signal "IN5")
		(30 "In14.Cu" signal "GND6")
		(32 "In15.Cu" signal "IN6")
		(34 "In16.Cu" signal "GND7")
		(2 "B.Cu" signal "BOTTOM")
		(9 "F.Adhes" user "F.Adhesive")
		(11 "B.Adhes" user "B.Adhesive")
		(13 "F.Paste" user "Package Geometry/Pastemask Top")
		(15 "B.Paste" user "Package Geometry/Pastemask Bottom")
		(5 "F.SilkS" user "Ref Des/Silkscreen Top")
		(7 "B.SilkS" user "Ref Des/Silkscreen Bottom")
		(1 "F.Mask" user "Board Geometry/Soldermask Top")
		(3 "B.Mask" user "Board Geometry/Soldermask Bottom")
		(17 "Dwgs.User" user "User.Drawings")
		(19 "Cmts.User" user "User.Comments")
		(21 "Eco1.User" user "User.Eco1")
		(23 "Eco2.User" user "User.Eco2")
		(25 "Edge.Cuts" user "Board Geometry/Outline")
		(27 "Margin" user)
		(31 "F.CrtYd" user "Package Geometry/Place Bound Top")
		(29 "B.CrtYd" user "Package Geometry/Place Bound Bottom")
		(35 "F.Fab" user "Ref Des/Assembly Top")
		(33 "B.Fab" user "Ref Des/Assembly Bottom")
	)
	(footprint ""
		(layer "B.Cu")
		(at 166.327582 -413.847788 90)
		(property "Reference" "Q128"
			(at -1.578102 2.42443 270)
			(unlocked yes)
			(layer "B.SilkS")
			(effects
				(font
					(size 0.7874 0.5842)
					(thickness 0.1524)
				)
				(justify left mirror)
			)
		)
		(property "Value" ""
			(at 0 0 90)
			(layer "B.Fab")
			(effects
				(font
					(size 1.27 1.27)
				)
				(justify mirror)
			)
		)
		(duplicate_pad_numbers_are_jumpers no)
		(fp_line
			(start 1.332738 -1.100074)
			(end 0.4826 -1.100074)
			(stroke
				(width 0.1524)
				(type default)
			)
			(layer "B.SilkS")
		)
		(fp_line
			(start 0.4826 -1.100074)
			(end 0 -0.541274)
			(stroke
				(width 0.1524)
				(type default)
			)
			(layer "B.SilkS")
		)
		(fp_line
			(start -0.4826 -1.100074)
			(end -1.332738 -1.100074)
			(stroke
				(width 0.1524)
				(type default)
			)
			(layer "B.SilkS")
		)
		(fp_line
			(start -1.332738 -1.100074)
			(end -1.332738 1.100074)
			(stroke
				(width 0.1524)
				(type default)
			)
			(layer "B.SilkS")
		)
		(fp_line
			(start 0 -0.541274)
			(end -0.4826 -1.100074)
			(stroke
				(width 0.1524)
				(type default)
			)
			(layer "B.SilkS")
		)
		(fp_line
			(start 1.332738 1.100074)
			(end 1.332738 -1.100074)
			(stroke
				(width 0.1524)
				(type default)
			)
			(layer "B.SilkS")
		)
		(fp_line
			(start -1.332738 1.100074)
			(end 1.332738 1.100074)
			(stroke
				(width 0.1524)
				(type default)
			)
			(layer "B.SilkS")
		)
		(fp_poly
			(pts
				(xy 1.463802 -1.014476) (xy 2.165604 -0.663448) (xy 2.165604 -1.365504)
			)
			(stroke
				(width 0)
				(type default)
			)
			(fill yes)
			(layer "B.SilkS")
		)
		(fp_line
			(start 0.674878 -1.100074)
			(end -0.674878 -1.100074)
			(stroke
				(width 0.1)
				(type default)
			)
			(layer "B.Fab")
		)
		(fp_line
			(start -0.674878 -1.100074)
			(end -0.674878 1.100074)
			(stroke
				(width 0.1)
				(type default)
			)
			(layer "B.Fab")
		)
		(fp_line
			(start 0.674878 1.100074)
			(end 0.674878 -1.100074)
			(stroke
				(width 0.1)
				(type default)
			)
			(layer "B.Fab")
		)
		(fp_line
			(start -0.674878 1.100074)
			(end 0.674878 1.100074)
			(stroke
				(width 0.1)
				(type default)
			)
			(layer "B.Fab")
		)
		(fp_poly
			(pts
				(xy 2.2352 -0.298958) (xy 2.2352 -1.001014) (xy 1.533144 -0.649986)
			)
			(stroke
				(width 0)
				(type default)
			)
			(fill yes)
			(layer "B.Fab")
		)
		(pad "1" smd rect
			(at 0.94996 -0.649986 180)
			(size 0.4318 0.508)
			(layers "B.Cu" "B.Mask" "B.Paste")
			(net "GND")
		)
		(pad "2" smd rect
			(at 0.94996 0 180)
			(size 0.4318 0.508)
			(layers "B.Cu" "B.Mask" "B.Paste")
			(net "GPU_3V3IO_RSVD0_FFU")
		)
		(pad "3" smd rect
			(at 0.94996 0.649986 180)
			(size 0.4318 0.508)
			(layers "B.Cu" "B.Mask" "B.Paste")
			(net "GPU_3V3IO_RSVD0_FFU_ISO")
		)
		(pad "4" smd rect
			(at -0.94996 0.649986 180)
			(size 0.4318 0.508)
			(layers "B.Cu" "B.Mask" "B.Paste")
			(net "GND")
		)
		(pad "5" smd rect
			(at -0.94996 0 180)
			(size 0.4318 0.508)
			(layers "B.Cu" "B.Mask" "B.Paste")
			(net "GPU_3V3IO_RSVD0_FFU_N")
		)
		(pad "6" smd rect
			(at -0.94996 -0.649986 180)
			(size 0.4318 0.508)
			(layers "B.Cu" "B.Mask" "B.Paste")
			(net "GPU_3V3IO_RSVD0_FFU_N")
		)
	)
	(footprint ""
		(layer "B.Cu")
		(at 125.262386 -266.005564)
		(property "Reference" "C2126"
			(at 0 0 0)
			(layer "B.SilkS")
			(hide yes)
			(effects
				(font
					(size 1.27 1.27)
				)
				(justify mirror)
			)
		)
		(property "Value" ""
			(at 0 0 0)
			(layer "B.Fab")
			(effects
				(font
					(size 1.27 1.27)
				)
				(justify mirror)
			)
		)
		(duplicate_pad_numbers_are_jumpers no)
		(fp_line
			(start -0.7874 -0.4064)
			(end -0.7874 0.4064)
			(stroke
				(width 0.1524)
				(type default)
			)
			(layer "B.SilkS")
		)
		(fp_line
			(start -0.7874 0.4064)
			(end 0.7874 0.4064)
			(stroke
				(width 0.1524)
				(type default)
			)
			(layer "B.SilkS")
		)
		(fp_line
			(start 0.7874 -0.4064)
			(end -0.7874 -0.4064)
			(stroke
				(width 0.1524)
				(type default)
			)
			(layer "B.SilkS")
		)
		(fp_line
			(start 0.7874 0.4064)
			(end 0.7874 -0.4064)
			(stroke
				(width 0.1524)
				(type default)
			)
			(layer "B.SilkS")
		)
		(fp_line
			(start -0.67945 -0.3048)
			(end -0.67945 0.3048)
			(stroke
				(width 0.1)
				(type default)
			)
			(layer "B.Fab")
		)
		(fp_line
			(start -0.67945 0.3048)
			(end -0.120396 0.3048)
			(stroke
				(width 0.1)
				(type default)
			)
			(layer "B.Fab")
		)
		(fp_line
			(start -0.12065 -0.3048)
			(end -0.67945 -0.3048)
			(stroke
				(width 0.1)
				(type default)
			)
			(layer "B.Fab")
		)
		(fp_line
			(start -0.12065 -0.2794)
			(end -0.12065 -0.3048)
			(stroke
				(width 0.1)
				(type default)
			)
			(layer "B.Fab")
		)
		(fp_line
			(start -0.120396 0.2794)
			(end 0.12065 0.2794)
			(stroke
				(width 0.1)
				(type default)
			)
			(layer "B.Fab")
		)
		(fp_line
			(start -0.120396 0.3048)
			(end -0.120396 0.2794)
			(stroke
				(width 0.1)
				(type default)
			)
			(layer "B.Fab")
		)
		(fp_line
			(start 0.12065 -0.305054)
			(end 0.12065 -0.2794)
			(stroke
				(width 0.1)
				(type default)
			)
			(layer "B.Fab")
		)
		(fp_line
			(start 0.12065 -0.2794)
			(end -0.12065 -0.2794)
			(stroke
				(width 0.1)
				(type default)
			)
			(layer "B.Fab")
		)
		(fp_line
			(start 0.12065 0.2794)
			(end 0.12065 0.3048)
			(stroke
				(width 0.1)
				(type default)
			)
			(layer "B.Fab")
		)
		(fp_line
			(start 0.12065 0.3048)
			(end 0.67945 0.3048)
			(stroke
				(width 0.1)
				(type default)
			)
			(layer "B.Fab")
		)
		(fp_line
			(start 0.67945 -0.305054)
			(end 0.12065 -0.305054)
			(stroke
				(width 0.1)
				(type default)
			)
			(layer "B.Fab")
		)
		(fp_line
			(start 0.67945 0.3048)
			(end 0.67945 -0.305054)
			(stroke
				(width 0.1)
				(type default)
			)
			(layer "B.Fab")
		)
		(pad "1" smd circle
			(at 0.40005 0 180)
			(size 0 0)
			(layers "B.Cu" "B.Mask" "B.Paste")
			(net "PVDD11_S3_P1")
		)
		(pad "2" smd circle
			(at -0.40005 0 180)
			(size 0 0)
			(layers "B.Cu" "B.Mask" "B.Paste")
			(net "GND")
		)
	)
)
